# T6G (Grand Teton) — schematic netlist excerpt (pin names and nets, part order shuffled) for the footprints in the layout excerpt that follows; sources: Cadence DE-HDL packaged netlist, KiCad conversion of 04192023_DAF0TMB3IC0_F0TG_MB_C_brd_V02_OCP.brd

Q9003  MOSFET_NCH_DUAL  PJT138K IC  pkg SOT363XD  page 85
  S1  = GND
  G1  = IRQ_HSC_FAULT_N
  D2  = IRQ_HSC_FAULT_BUF_N
  S2  = GND
  G2  = IRQ_HSC_FAULT
  D1  = IRQ_HSC_FAULT

R3270  Q_RES  1K 1% EMPTY  pkg 0402LF  page 111 : A = FM_P2E_FGB ; B = GND

(kicad_pcb
	(version 20260206)
	(generator "pcbnew")
	(generator_version "10.0")
	(general
		(thickness 1.6)
		(legacy_teardrops no)
	)
	(paper "A4")
	(title_block
		(title "04192023_DAF0TMB3IC0_F0TG_MB_C_brd_V02_OCP.brd")
		(comment 1 "Grand Teton / footprints 2854-2855 of 8354")
	)
	(layers
		(0 "F.Cu" signal "TOP")
		(4 "In1.Cu" signal "GND")
		(6 "In2.Cu" signal "IN1")
		(8 "In3.Cu" signal "GND1")
		(10 "In4.Cu" signal "IN2")
		(12 "In5.Cu" signal "GND2")
		(14 "In6.Cu" signal "IN3")
		(16 "In7.Cu" signal "GND3")
		(18 "In8.Cu" signal "VCC")
		(20 "In9.Cu" signal "VCC1")
		(22 "In10.Cu" signal "GND4")
		(24 "In11.Cu" signal "IN4")
		(26 "In12.Cu" signal "GND5")
		(28 "In13.Cu" signal "IN5")
		(30 "In14.Cu" signal "GND6")
		(32 "In15.Cu" signal "IN6")
		(34 "In16.Cu" signal "GND7")
		(2 "B.Cu" signal "BOTTOM")
		(9 "F.Adhes" user "F.Adhesive")
		(11 "B.Adhes" user "B.Adhesive")
		(13 "F.Paste" user "Package Geometry/Pastemask Top")
		(15 "B.Paste" user "Package Geometry/Pastemask Bottom")
		(5 "F.SilkS" user "Ref Des/Silkscreen Top")
		(7 "B.SilkS" user "Ref Des/Silkscreen Bottom")
		(1 "F.Mask" user "Board Geometry/Soldermask Top")
		(3 "B.Mask" user "Board Geometry/Soldermask Bottom")
		(17 "Dwgs.User" user "User.Drawings")
		(19 "Cmts.User" user "User.Comments")
		(21 "Eco1.User" user "User.Eco1")
		(23 "Eco2.User" user "User.Eco2")
		(25 "Edge.Cuts" user "Board Geometry/Outline")
		(27 "Margin" user)
		(31 "F.CrtYd" user "Package Geometry/Place Bound Top")
		(29 "B.CrtYd" user "Package Geometry/Place Bound Bottom")
		(35 "F.Fab" user "Ref Des/Assembly Top")
		(33 "B.Fab" user "Ref Des/Assembly Bottom")
	)
	(footprint ""
		(layer "F.Cu")
		(at 33.363662 -429.790098 90)
		(property "Reference" "R3270"
			(at 0 0 90)
			(layer "F.SilkS")
			(hide yes)
			(effects
				(font
					(size 1.27 1.27)
				)
			)
		)
		(property "Value" ""
			(at 0 0 90)
			(layer "F.Fab")
			(effects
				(font
					(size 1.27 1.27)
				)
			)
		)
		(duplicate_pad_numbers_are_jumpers no)
		(fp_line
			(start 0.7874 -0.4064)
			(end 0.7874 0.4064)
			(stroke
				(width 0.1524)
				(type default)
			)
			(layer "F.SilkS")
		)
		(fp_line
			(start -0.7874 -0.4064)
			(end 0.7874 -0.4064)
			(stroke
				(width 0.1524)
				(type default)
			)
			(layer "F.SilkS")
		)
		(fp_line
			(start 0.7874 0.4064)
			(end -0.7874 0.4064)
			(stroke
				(width 0.1524)
				(type default)
			)
			(layer "F.SilkS")
		)
		(fp_line
			(start -0.7874 0.4064)
			(end -0.7874 -0.4064)
			(stroke
				(width 0.1524)
				(type default)
			)
			(layer "F.SilkS")
		)
		(fp_line
			(start -0.12065 -0.305054)
			(end -0.12065 -0.2794)
			(stroke
				(width 0.1)
				(type default)
			)
			(layer "F.Fab")
		)
		(fp_line
			(start -0.67945 -0.305054)
			(end -0.12065 -0.305054)
			(stroke
				(width 0.1)
				(type default)
			)
			(layer "F.Fab")
		)
		(fp_line
			(start 0.67945 -0.3048)
			(end 0.67945 0.3048)
			(stroke
				(width 0.1)
				(type default)
			)
			(layer "F.Fab")
		)
		(fp_line
			(start 0.12065 -0.3048)
			(end 0.67945 -0.3048)
			(stroke
				(width 0.1)
				(type default)
			)
			(layer "F.Fab")
		)
		(fp_line
			(start 0.12065 -0.2794)
			(end 0.12065 -0.3048)
			(stroke
				(width 0.1)
				(type default)
			)
			(layer "F.Fab")
		)
		(fp_line
			(start -0.12065 -0.2794)
			(end 0.12065 -0.2794)
			(stroke
				(width 0.1)
				(type default)
			)
			(layer "F.Fab")
		)
		(fp_line
			(start 0.120396 0.2794)
			(end -0.12065 0.2794)
			(stroke
				(width 0.1)
				(type default)
			)
			(layer "F.Fab")
		)
		(fp_line
			(start -0.12065 0.2794)
			(end -0.12065 0.3048)
			(stroke
				(width 0.1)
				(type default)
			)
			(layer "F.Fab")
		)
		(fp_line
			(start 0.67945 0.3048)
			(end 0.120396 0.3048)
			(stroke
				(width 0.1)
				(type default)
			)
			(layer "F.Fab")
		)
		(fp_line
			(start 0.120396 0.3048)
			(end 0.120396 0.2794)
			(stroke
				(width 0.1)
				(type default)
			)
			(layer "F.Fab")
		)
		(fp_line
			(start -0.12065 0.3048)
			(end -0.67945 0.3048)
			(stroke
				(width 0.1)
				(type default)
			)
			(layer "F.Fab")
		)
		(fp_line
			(start -0.67945 0.3048)
			(end -0.67945 -0.305054)
			(stroke
				(width 0.1)
				(type default)
			)
			(layer "F.Fab")
		)
		(pad "1" smd circle
			(at -0.40005 0 90)
			(size 0 0)
			(layers "F.Cu" "F.Mask" "F.Paste")
			(net "FM_P2E_FGB")
		)
		(pad "2" smd circle
			(at 0.40005 0 90)
			(size 0 0)
			(layers "F.Cu" "F.Mask" "F.Paste")
			(net "GND")
		)
	)
	(footprint ""
		(layer "F.Cu")
		(at 159.639 -106.426 180)
		(property "Reference" "Q9003"
			(at 2.59461 -2.129028 0)
			(unlocked yes)
			(layer "F.SilkS")
			(effects
				(font
					(size 0.7874 0.5842)
					(thickness 0.1524)
				)
				(justify left)
			)
		)
		(property "Value" ""
			(at 0 0 180)
			(layer "F.Fab")
			(effects
				(font
					(size 1.27 1.27)
				)
			)
		)
		(duplicate_pad_numbers_are_jumpers no)
		(fp_line
			(start 1.332738 1.100074)
			(end -1.332738 1.100074)
			(stroke
				(width 0.1524)
				(type default)
			)
			(layer "F.SilkS")
		)
		(fp_line
			(start 1.332738 -1.100074)
			(end 1.332738 1.100074)
			(stroke
				(width 0.1524)
				(type default)
			)
			(layer "F.SilkS")
		)
		(fp_line
			(start 0.4826 -1.100074)
			(end 1.332738 -1.100074)
			(stroke
				(width 0.1524)
				(type default)
			)
			(layer "F.SilkS")
		)
		(fp_line
			(start 0 -0.541274)
			(end 0.4826 -1.100074)
			(stroke
				(width 0.1524)
				(type default)
			)
			(layer "F.SilkS")
		)
		(fp_line
			(start -0.4826 -1.100074)
			(end 0 -0.541274)
			(stroke
				(width 0.1524)
				(type default)
			)
			(layer "F.SilkS")
		)
		(fp_line
			(start -1.332738 1.100074)
			(end -1.332738 -1.100074)
			(stroke
				(width 0.1524)
				(type default)
			)
			(layer "F.SilkS")
		)
		(fp_line
			(start -1.332738 -1.100074)
			(end -0.4826 -1.100074)
			(stroke
				(width 0.1524)
				(type default)
			)
			(layer "F.SilkS")
		)
		(fp_poly
			(pts
				(xy -2.28219 -1.735074) (xy -1.785874 -2.23139) (xy -1.537716 -1.486916)
			)
			(stroke
				(width 0)
				(type default)
			)
			(fill yes)
			(layer "F.SilkS")
		)
		(fp_line
			(start 0.674878 1.100074)
			(end -0.674878 1.100074)
			(stroke
				(width 0.1)
				(type default)
			)
			(layer "F.Fab")
		)
		(fp_line
			(start 0.674878 -1.100074)
			(end 0.674878 1.100074)
			(stroke
				(width 0.1)
				(type default)
			)
			(layer "F.Fab")
		)
		(fp_line
			(start -0.674878 1.100074)
			(end -0.674878 -1.100074)
			(stroke
				(width 0.1)
				(type default)
			)
			(layer "F.Fab")
		)
		(fp_line
			(start -0.674878 -1.100074)
			(end 0.674878 -1.100074)
			(stroke
				(width 0.1)
				(type default)
			)
			(layer "F.Fab")
		)
		(fp_poly
			(pts
				(xy -2.2352 -0.298958) (xy -2.2352 -1.001014) (xy -1.533144 -0.649986)
			)
			(stroke
				(width 0)
				(type default)
			)
			(fill yes)
			(layer "F.Fab")
		)
		(pad "1" smd rect
			(at -0.94996 -0.649986 270)
			(size 0.4318 0.508)
			(layers "F.Cu" "F.Mask" "F.Paste")
			(net "GND")
		)
		(pad "2" smd rect
			(at -0.94996 0 270)
			(size 0.4318 0.508)
			(layers "F.Cu" "F.Mask" "F.Paste")
			(net "IRQ_HSC_FAULT_N")
		)
		(pad "3" smd rect
			(at -0.94996 0.649986 270)
			(size 0.4318 0.508)
			(layers "F.Cu" "F.Mask" "F.Paste")
			(net "IRQ_HSC_FAULT_BUF_N")
		)
		(pad "4" smd rect
			(at 0.94996 0.649986 270)
			(size 0.4318 0.508)
			(layers "F.Cu" "F.Mask" "F.Paste")
			(net "GND")
		)
		(pad "5" smd rect
			(at 0.94996 0 270)
			(size 0.4318 0.508)
			(layers "F.Cu" "F.Mask" "F.Paste")
			(net "IRQ_HSC_FAULT")
		)
		(pad "6" smd rect
			(at 0.94996 -0.649986 270)
			(size 0.4318 0.508)
			(layers "F.Cu" "F.Mask" "F.Paste")
			(net "IRQ_HSC_FAULT")
		)
	)
)
